(kicad_pcb
	(version 20260206)
	(generator "pcbnew")
	(generator_version "10.0")
	(general
		(thickness 1.6)
		(legacy_teardrops no)
	)
	(paper "A4")
	(title_block
		(title "03242023_DA0F0TMBIJ0_F0T_Motherboard_J_brd_V01_OCP.brd")
		(comment 1 "Grand Teton / footprint 1236 of 6105 (J1), pads 113-224 of 291")
	)
	(layers
		(0 "F.Cu" signal "TOP")
		(4 "In1.Cu" signal "GND")
		(6 "In2.Cu" signal "IN1")
		(8 "In3.Cu" signal "GND1")
		(10 "In4.Cu" signal "IN2")
		(12 "In5.Cu" signal "GND2")
		(14 "In6.Cu" signal "IN3")
		(16 "In7.Cu" signal "GND3")
		(18 "In8.Cu" signal "VCC")
		(20 "In9.Cu" signal "VCC1")
		(22 "In10.Cu" signal "GND4")
		(24 "In11.Cu" signal "IN4")
		(26 "In12.Cu" signal "GND5")
		(28 "In13.Cu" signal "IN5")
		(30 "In14.Cu" signal "GND6")
		(32 "In15.Cu" signal "IN6")
		(34 "In16.Cu" signal "GND7")
		(2 "B.Cu" signal "BOTTOM")
		(9 "F.Adhes" user "F.Adhesive")
		(11 "B.Adhes" user "B.Adhesive")
		(13 "F.Paste" user "Package Geometry/Pastemask Top")
		(15 "B.Paste" user "Package Geometry/Pastemask Bottom")
		(5 "F.SilkS" user "Ref Des/Silkscreen Top")
		(7 "B.SilkS" user "Ref Des/Silkscreen Bottom")
		(1 "F.Mask" user "Board Geometry/Soldermask Top")
		(3 "B.Mask" user "Board Geometry/Soldermask Bottom")
		(17 "Dwgs.User" user "User.Drawings")
		(19 "Cmts.User" user "User.Comments")
		(21 "Eco1.User" user "User.Eco1")
		(23 "Eco2.User" user "User.Eco2")
		(25 "Edge.Cuts" user "Board Geometry/Outline")
		(27 "Margin" user)
		(31 "F.CrtYd" user "Package Geometry/Place Bound Top")
		(29 "B.CrtYd" user "Package Geometry/Place Bound Bottom")
		(35 "F.Fab" user "Ref Des/Assembly Top")
		(33 "B.Fab" user "Ref Des/Assembly Bottom")
	)
	(footprint ""
		(layer "F.Cu")
		(at 303.393348 -258.091686)
		(property "Reference" "J1"
			(at -3.683 -81.702148 0)
			(unlocked yes)
			(layer "F.SilkS")
			(effects
				(font
					(size 0.7874 0.5842)
					(thickness 0.1524)
				)
				(justify left)
			)
		)
		(property "Value" ""
			(at 0 0 0)
			(layer "F.Fab")
			(effects
				(font
					(size 1.27 1.27)
				)
			)
		)
		(duplicate_pad_numbers_are_jumpers no)
		(pad "113" smd rect
			(at -2.050034 36.975034 270)
			(size 0.519938 1.4986)
			(layers "F.Cu" "F.Mask" "F.Paste")
			(net "M_A_CPU0_SB_DQ<9>")
		)
		(pad "114" smd rect
			(at -2.050034 37.824918 270)
			(size 0.519938 1.4986)
			(layers "F.Cu" "F.Mask" "F.Paste")
			(net "GND")
		)
		(pad "115" smd rect
			(at -2.050034 38.675056 270)
			(size 0.519938 1.4986)
			(layers "F.Cu" "F.Mask" "F.Paste")
			(net "M_A_CPU0_SB_DQS_DP<1>")
		)
		(pad "116" smd rect
			(at -2.050034 39.52494 270)
			(size 0.519938 1.4986)
			(layers "F.Cu" "F.Mask" "F.Paste")
			(net "M_A_CPU0_SB_DQS_DN<1>")
		)
		(pad "117" smd rect
			(at -2.050034 40.375078 270)
			(size 0.519938 1.4986)
			(layers "F.Cu" "F.Mask" "F.Paste")
			(net "GND")
		)
		(pad "118" smd rect
			(at -2.050034 41.224962 270)
			(size 0.519938 1.4986)
			(layers "F.Cu" "F.Mask" "F.Paste")
			(net "M_A_CPU0_SB_DQ<12>")
		)
		(pad "119" smd rect
			(at -2.050034 42.0751 270)
			(size 0.519938 1.4986)
			(layers "F.Cu" "F.Mask" "F.Paste")
			(net "GND")
		)
		(pad "120" smd rect
			(at -2.050034 42.924984 270)
			(size 0.519938 1.4986)
			(layers "F.Cu" "F.Mask" "F.Paste")
			(net "M_A_CPU0_SB_DQ<13>")
		)
		(pad "121" smd rect
			(at -2.050034 43.775122 270)
			(size 0.519938 1.4986)
			(layers "F.Cu" "F.Mask" "F.Paste")
			(net "GND")
		)
		(pad "122" smd rect
			(at -2.050034 44.625006 270)
			(size 0.519938 1.4986)
			(layers "F.Cu" "F.Mask" "F.Paste")
			(net "M_A_CPU0_SB_DQ<16>")
		)
		(pad "123" smd rect
			(at -2.050034 45.47489 270)
			(size 0.519938 1.4986)
			(layers "F.Cu" "F.Mask" "F.Paste")
			(net "GND")
		)
		(pad "124" smd rect
			(at -2.050034 46.325028 270)
			(size 0.519938 1.4986)
			(layers "F.Cu" "F.Mask" "F.Paste")
			(net "M_A_CPU0_SB_DQ<17>")
		)
		(pad "125" smd rect
			(at -2.050034 47.174912 270)
			(size 0.519938 1.4986)
			(layers "F.Cu" "F.Mask" "F.Paste")
			(net "GND")
		)
		(pad "126" smd rect
			(at -2.050034 48.02505 270)
			(size 0.519938 1.4986)
			(layers "F.Cu" "F.Mask" "F.Paste")
			(net "M_A_CPU0_SB_DQS_DP<2>")
		)
		(pad "127" smd rect
			(at -2.050034 48.874934 270)
			(size 0.519938 1.4986)
			(layers "F.Cu" "F.Mask" "F.Paste")
			(net "M_A_CPU0_SB_DQS_DN<2>")
		)
		(pad "128" smd rect
			(at -2.050034 49.725072 270)
			(size 0.519938 1.4986)
			(layers "F.Cu" "F.Mask" "F.Paste")
			(net "GND")
		)
		(pad "129" smd rect
			(at -2.050034 50.574956 270)
			(size 0.519938 1.4986)
			(layers "F.Cu" "F.Mask" "F.Paste")
			(net "M_A_CPU0_SB_DQ<20>")
		)
		(pad "130" smd rect
			(at -2.050034 51.425094 270)
			(size 0.519938 1.4986)
			(layers "F.Cu" "F.Mask" "F.Paste")
			(net "GND")
		)
		(pad "131" smd rect
			(at -2.050034 52.274978 270)
			(size 0.519938 1.4986)
			(layers "F.Cu" "F.Mask" "F.Paste")
			(net "M_A_CPU0_SB_DQ<21>")
		)
		(pad "132" smd rect
			(at -2.050034 53.125116 270)
			(size 0.519938 1.4986)
			(layers "F.Cu" "F.Mask" "F.Paste")
			(net "GND")
		)
		(pad "133" smd rect
			(at -2.050034 53.975 270)
			(size 0.519938 1.4986)
			(layers "F.Cu" "F.Mask" "F.Paste")
			(net "M_A_CPU0_SB_DQ<24>")
		)
		(pad "134" smd rect
			(at -2.050034 54.824884 270)
			(size 0.519938 1.4986)
			(layers "F.Cu" "F.Mask" "F.Paste")
			(net "GND")
		)
		(pad "135" smd rect
			(at -2.050034 55.675022 270)
			(size 0.519938 1.4986)
			(layers "F.Cu" "F.Mask" "F.Paste")
			(net "M_A_CPU0_SB_DQ<25>")
		)
		(pad "136" smd rect
			(at -2.050034 56.524906 270)
			(size 0.519938 1.4986)
			(layers "F.Cu" "F.Mask" "F.Paste")
			(net "GND")
		)
		(pad "137" smd rect
			(at -2.050034 57.375044 270)
			(size 0.519938 1.4986)
			(layers "F.Cu" "F.Mask" "F.Paste")
			(net "M_A_CPU0_SB_DQS_DP<3>")
		)
		(pad "138" smd rect
			(at -2.050034 58.224928 270)
			(size 0.519938 1.4986)
			(layers "F.Cu" "F.Mask" "F.Paste")
			(net "M_A_CPU0_SB_DQS_DN<3>")
		)
		(pad "139" smd rect
			(at -2.050034 59.075066 270)
			(size 0.519938 1.4986)
			(layers "F.Cu" "F.Mask" "F.Paste")
			(net "GND")
		)
		(pad "140" smd rect
			(at -2.050034 59.92495 270)
			(size 0.519938 1.4986)
			(layers "F.Cu" "F.Mask" "F.Paste")
			(net "M_A_CPU0_SB_DQ<28>")
		)
		(pad "141" smd rect
			(at -2.050034 60.775088 270)
			(size 0.519938 1.4986)
			(layers "F.Cu" "F.Mask" "F.Paste")
			(net "GND")
		)
		(pad "142" smd rect
			(at -2.050034 61.624972 270)
			(size 0.519938 1.4986)
			(layers "F.Cu" "F.Mask" "F.Paste")
			(net "M_A_CPU0_SB_DQ<29>")
		)
		(pad "143" smd rect
			(at -2.050034 62.47511 270)
			(size 0.519938 1.4986)
			(layers "F.Cu" "F.Mask" "F.Paste")
			(net "GND")
		)
		(pad "144" smd rect
			(at -2.050034 63.324994 270)
			(size 0.519938 1.4986)
			(layers "F.Cu" "F.Mask" "F.Paste")
			(net "TP_CHA_CPU0_DIMM1_FRU_1")
		)
		(pad "145" smd rect
			(at 2.050034 -63.324994 270)
			(size 0.519938 1.4986)
			(layers "F.Cu" "F.Mask" "F.Paste")
			(net "P12V_S3_AUX_CPU0_NVDIMM")
		)
		(pad "146" smd rect
			(at 2.050034 -62.47511 270)
			(size 0.519938 1.4986)
			(layers "F.Cu" "F.Mask" "F.Paste")
			(net "P12V_S3_AUX_CPU0_NVDIMM")
		)
		(pad "147" smd rect
			(at 2.050034 -61.624972 270)
			(size 0.519938 1.4986)
			(layers "F.Cu" "F.Mask" "F.Paste")
			(net "PWRGD_CHA_CPU0_DIMM1")
		)
		(pad "148" smd rect
			(at 2.050034 -60.775088 270)
			(size 0.519938 1.4986)
			(layers "F.Cu" "F.Mask" "F.Paste")
			(net "PD_CHA_CPU0_DIMM1_SAA")
		)
		(pad "149" smd rect
			(at 2.050034 -59.92495 270)
			(size 0.519938 1.4986)
			(layers "F.Cu" "F.Mask" "F.Paste")
			(net "TP_CHA_CPU0_DIMM1_FRU_2")
		)
		(pad "150" smd rect
			(at 2.050034 -59.075066 270)
			(size 0.519938 1.4986)
			(layers "F.Cu" "F.Mask" "F.Paste")
			(net "TP_CHA_CPU0_DIMM1_FRU_3")
		)
		(pad "151" smd rect
			(at 2.050034 -58.224928 270)
			(size 0.519938 1.4986)
			(layers "F.Cu" "F.Mask" "F.Paste")
			(net "GND")
		)
		(pad "152" smd rect
			(at 2.050034 -57.375044 270)
			(size 0.519938 1.4986)
			(layers "F.Cu" "F.Mask" "F.Paste")
			(net "M_A_CPU0_SA_DQ<2>")
		)
		(pad "153" smd rect
			(at 2.050034 -56.524906 270)
			(size 0.519938 1.4986)
			(layers "F.Cu" "F.Mask" "F.Paste")
			(net "GND")
		)
		(pad "154" smd rect
			(at 2.050034 -55.675022 270)
			(size 0.519938 1.4986)
			(layers "F.Cu" "F.Mask" "F.Paste")
			(net "M_A_CPU0_SA_DQ<3>")
		)
		(pad "155" smd rect
			(at 2.050034 -54.824884 270)
			(size 0.519938 1.4986)
			(layers "F.Cu" "F.Mask" "F.Paste")
			(net "GND")
		)
		(pad "156" smd rect
			(at 2.050034 -53.975 270)
			(size 0.519938 1.4986)
			(layers "F.Cu" "F.Mask" "F.Paste")
			(net "M_A_CPU0_SA_DQS_DN<5>")
		)
		(pad "157" smd rect
			(at 2.050034 -53.125116 270)
			(size 0.519938 1.4986)
			(layers "F.Cu" "F.Mask" "F.Paste")
			(net "M_A_CPU0_SA_DQS_DP<5>")
		)
		(pad "158" smd rect
			(at 2.050034 -52.274978 270)
			(size 0.519938 1.4986)
			(layers "F.Cu" "F.Mask" "F.Paste")
			(net "GND")
		)
		(pad "159" smd rect
			(at 2.050034 -51.425094 270)
			(size 0.519938 1.4986)
			(layers "F.Cu" "F.Mask" "F.Paste")
			(net "M_A_CPU0_SA_DQ<6>")
		)
		(pad "160" smd rect
			(at 2.050034 -50.574956 270)
			(size 0.519938 1.4986)
			(layers "F.Cu" "F.Mask" "F.Paste")
			(net "GND")
		)
		(pad "161" smd rect
			(at 2.050034 -49.725072 270)
			(size 0.519938 1.4986)
			(layers "F.Cu" "F.Mask" "F.Paste")
			(net "M_A_CPU0_SA_DQ<7>")
		)
		(pad "162" smd rect
			(at 2.050034 -48.874934 270)
			(size 0.519938 1.4986)
			(layers "F.Cu" "F.Mask" "F.Paste")
			(net "GND")
		)
		(pad "163" smd rect
			(at 2.050034 -48.02505 270)
			(size 0.519938 1.4986)
			(layers "F.Cu" "F.Mask" "F.Paste")
			(net "M_A_CPU0_SA_DQ<10>")
		)
		(pad "164" smd rect
			(at 2.050034 -47.174912 270)
			(size 0.519938 1.4986)
			(layers "F.Cu" "F.Mask" "F.Paste")
			(net "GND")
		)
		(pad "165" smd rect
			(at 2.050034 -46.325028 270)
			(size 0.519938 1.4986)
			(layers "F.Cu" "F.Mask" "F.Paste")
			(net "M_A_CPU0_SA_DQ<11>")
		)
		(pad "166" smd rect
			(at 2.050034 -45.47489 270)
			(size 0.519938 1.4986)
			(layers "F.Cu" "F.Mask" "F.Paste")
			(net "GND")
		)
		(pad "167" smd rect
			(at 2.050034 -44.625006 270)
			(size 0.519938 1.4986)
			(layers "F.Cu" "F.Mask" "F.Paste")
			(net "M_A_CPU0_SA_DQS_DN<6>")
		)
		(pad "168" smd rect
			(at 2.050034 -43.775122 270)
			(size 0.519938 1.4986)
			(layers "F.Cu" "F.Mask" "F.Paste")
			(net "M_A_CPU0_SA_DQS_DP<6>")
		)
		(pad "169" smd rect
			(at 2.050034 -42.924984 270)
			(size 0.519938 1.4986)
			(layers "F.Cu" "F.Mask" "F.Paste")
			(net "GND")
		)
		(pad "170" smd rect
			(at 2.050034 -42.0751 270)
			(size 0.519938 1.4986)
			(layers "F.Cu" "F.Mask" "F.Paste")
			(net "M_A_CPU0_SA_DQ<14>")
		)
		(pad "171" smd rect
			(at 2.050034 -41.224962 270)
			(size 0.519938 1.4986)
			(layers "F.Cu" "F.Mask" "F.Paste")
			(net "GND")
		)
		(pad "172" smd rect
			(at 2.050034 -40.375078 270)
			(size 0.519938 1.4986)
			(layers "F.Cu" "F.Mask" "F.Paste")
			(net "M_A_CPU0_SA_DQ<15>")
		)
		(pad "173" smd rect
			(at 2.050034 -39.52494 270)
			(size 0.519938 1.4986)
			(layers "F.Cu" "F.Mask" "F.Paste")
			(net "GND")
		)
		(pad "174" smd rect
			(at 2.050034 -38.675056 270)
			(size 0.519938 1.4986)
			(layers "F.Cu" "F.Mask" "F.Paste")
			(net "M_A_CPU0_SA_DQ<18>")
		)
		(pad "175" smd rect
			(at 2.050034 -37.824918 270)
			(size 0.519938 1.4986)
			(layers "F.Cu" "F.Mask" "F.Paste")
			(net "GND")
		)
		(pad "176" smd rect
			(at 2.050034 -36.975034 270)
			(size 0.519938 1.4986)
			(layers "F.Cu" "F.Mask" "F.Paste")
			(net "M_A_CPU0_SA_DQ<19>")
		)
		(pad "177" smd rect
			(at 2.050034 -36.124896 270)
			(size 0.519938 1.4986)
			(layers "F.Cu" "F.Mask" "F.Paste")
			(net "GND")
		)
		(pad "178" smd rect
			(at 2.050034 -35.275012 270)
			(size 0.519938 1.4986)
			(layers "F.Cu" "F.Mask" "F.Paste")
			(net "M_A_CPU0_SA_DQS_DN<7>")
		)
		(pad "179" smd rect
			(at 2.050034 -34.425128 270)
			(size 0.519938 1.4986)
			(layers "F.Cu" "F.Mask" "F.Paste")
			(net "M_A_CPU0_SA_DQS_DP<7>")
		)
		(pad "180" smd rect
			(at 2.050034 -33.57499 270)
			(size 0.519938 1.4986)
			(layers "F.Cu" "F.Mask" "F.Paste")
			(net "GND")
		)
		(pad "181" smd rect
			(at 2.050034 -32.725106 270)
			(size 0.519938 1.4986)
			(layers "F.Cu" "F.Mask" "F.Paste")
			(net "M_A_CPU0_SA_DQ<22>")
		)
		(pad "182" smd rect
			(at 2.050034 -31.874968 270)
			(size 0.519938 1.4986)
			(layers "F.Cu" "F.Mask" "F.Paste")
			(net "GND")
		)
		(pad "183" smd rect
			(at 2.050034 -31.025084 270)
			(size 0.519938 1.4986)
			(layers "F.Cu" "F.Mask" "F.Paste")
			(net "M_A_CPU0_SA_DQ<23>")
		)
		(pad "184" smd rect
			(at 2.050034 -30.174946 270)
			(size 0.519938 1.4986)
			(layers "F.Cu" "F.Mask" "F.Paste")
			(net "GND")
		)
		(pad "185" smd rect
			(at 2.050034 -29.325062 270)
			(size 0.519938 1.4986)
			(layers "F.Cu" "F.Mask" "F.Paste")
			(net "M_A_CPU0_SA_DQ<26>")
		)
		(pad "186" smd rect
			(at 2.050034 -28.474924 270)
			(size 0.519938 1.4986)
			(layers "F.Cu" "F.Mask" "F.Paste")
			(net "GND")
		)
		(pad "187" smd rect
			(at 2.050034 -27.62504 270)
			(size 0.519938 1.4986)
			(layers "F.Cu" "F.Mask" "F.Paste")
			(net "M_A_CPU0_SA_DQ<27>")
		)
		(pad "188" smd rect
			(at 2.050034 -26.774902 270)
			(size 0.519938 1.4986)
			(layers "F.Cu" "F.Mask" "F.Paste")
			(net "GND")
		)
		(pad "189" smd rect
			(at 2.050034 -25.925018 270)
			(size 0.519938 1.4986)
			(layers "F.Cu" "F.Mask" "F.Paste")
			(net "M_A_CPU0_SA_DQS_DN<8>")
		)
		(pad "190" smd rect
			(at 2.050034 -25.07488 270)
			(size 0.519938 1.4986)
			(layers "F.Cu" "F.Mask" "F.Paste")
			(net "M_A_CPU0_SA_DQS_DP<8>")
		)
		(pad "191" smd rect
			(at 2.050034 -24.224996 270)
			(size 0.519938 1.4986)
			(layers "F.Cu" "F.Mask" "F.Paste")
			(net "GND")
		)
		(pad "192" smd rect
			(at 2.050034 -23.375112 270)
			(size 0.519938 1.4986)
			(layers "F.Cu" "F.Mask" "F.Paste")
			(net "M_A_CPU0_SA_DQ<30>")
		)
		(pad "193" smd rect
			(at 2.050034 -22.524974 270)
			(size 0.519938 1.4986)
			(layers "F.Cu" "F.Mask" "F.Paste")
			(net "GND")
		)
		(pad "194" smd rect
			(at 2.050034 -21.67509 270)
			(size 0.519938 1.4986)
			(layers "F.Cu" "F.Mask" "F.Paste")
			(net "M_A_CPU0_SA_DQ<31>")
		)
		(pad "195" smd rect
			(at 2.050034 -20.824952 270)
			(size 0.519938 1.4986)
			(layers "F.Cu" "F.Mask" "F.Paste")
			(net "GND")
		)
		(pad "196" smd rect
			(at 2.050034 -19.975068 270)
			(size 0.519938 1.4986)
			(layers "F.Cu" "F.Mask" "F.Paste")
			(net "M_A_CPU0_SA_CB<2>")
		)
		(pad "197" smd rect
			(at 2.050034 -19.12493 270)
			(size 0.519938 1.4986)
			(layers "F.Cu" "F.Mask" "F.Paste")
			(net "GND")
		)
		(pad "198" smd rect
			(at 2.050034 -18.275046 270)
			(size 0.519938 1.4986)
			(layers "F.Cu" "F.Mask" "F.Paste")
			(net "M_A_CPU0_SA_CB<3>")
		)
		(pad "199" smd rect
			(at 2.050034 -17.424908 270)
			(size 0.519938 1.4986)
			(layers "F.Cu" "F.Mask" "F.Paste")
			(net "GND")
		)
		(pad "200" smd rect
			(at 2.050034 -16.575024 270)
			(size 0.519938 1.4986)
			(layers "F.Cu" "F.Mask" "F.Paste")
			(net "M_A_CPU0_SA_DQS_DN<9>")
		)
		(pad "201" smd rect
			(at 2.050034 -15.724886 270)
			(size 0.519938 1.4986)
			(layers "F.Cu" "F.Mask" "F.Paste")
			(net "M_A_CPU0_SA_DQS_DP<9>")
		)
		(pad "202" smd rect
			(at 2.050034 -14.875002 270)
			(size 0.519938 1.4986)
			(layers "F.Cu" "F.Mask" "F.Paste")
			(net "GND")
		)
		(pad "203" smd rect
			(at 2.050034 -14.025118 270)
			(size 0.519938 1.4986)
			(layers "F.Cu" "F.Mask" "F.Paste")
			(net "M_A_CPU0_SA_CB<6>")
		)
		(pad "204" smd rect
			(at 2.050034 -13.17498 270)
			(size 0.519938 1.4986)
			(layers "F.Cu" "F.Mask" "F.Paste")
			(net "GND")
		)
		(pad "205" smd rect
			(at 2.050034 -12.325096 270)
			(size 0.519938 1.4986)
			(layers "F.Cu" "F.Mask" "F.Paste")
			(net "M_A_CPU0_SA_CB<7>")
		)
		(pad "206" smd rect
			(at 2.050034 -11.474958 270)
			(size 0.519938 1.4986)
			(layers "F.Cu" "F.Mask" "F.Paste")
			(net "GND")
		)
		(pad "207" smd rect
			(at 2.050034 -10.625074 270)
			(size 0.519938 1.4986)
			(layers "F.Cu" "F.Mask" "F.Paste")
			(net "RST_M_AB_CPU0_FPGA_N")
		)
		(pad "208" smd rect
			(at 2.050034 -9.774936 270)
			(size 0.519938 1.4986)
			(layers "F.Cu" "F.Mask" "F.Paste")
			(net "GND")
		)
		(pad "209" smd rect
			(at 2.050034 -8.925052 270)
			(size 0.519938 1.4986)
			(layers "F.Cu" "F.Mask" "F.Paste")
			(net "M_A_CPU0_SA_CS_N<1>")
		)
		(pad "210" smd rect
			(at 2.050034 -8.074914 270)
			(size 0.519938 1.4986)
			(layers "F.Cu" "F.Mask" "F.Paste")
			(net "GND")
		)
		(pad "211" smd rect
			(at 2.050034 -7.22503 270)
			(size 0.519938 1.4986)
			(layers "F.Cu" "F.Mask" "F.Paste")
			(net "M_A_CPU0_SA_CA<1>")
		)
		(pad "212" smd rect
			(at 2.050034 -6.374892 270)
			(size 0.519938 1.4986)
			(layers "F.Cu" "F.Mask" "F.Paste")
			(net "GND")
		)
		(pad "213" smd rect
			(at 2.050034 -5.525008 270)
			(size 0.519938 1.4986)
			(layers "F.Cu" "F.Mask" "F.Paste")
			(net "M_A_CPU0_SA_CA<3>")
		)
		(pad "214" smd rect
			(at 2.050034 -4.675124 270)
			(size 0.519938 1.4986)
			(layers "F.Cu" "F.Mask" "F.Paste")
			(net "GND")
		)
		(pad "215" smd rect
			(at 2.050034 -3.824986 270)
			(size 0.519938 1.4986)
			(layers "F.Cu" "F.Mask" "F.Paste")
			(net "M_A_CPU0_SA_CA<5>")
		)
		(pad "216" smd rect
			(at 2.050034 -2.975102 270)
			(size 0.519938 1.4986)
			(layers "F.Cu" "F.Mask" "F.Paste")
			(net "GND")
		)
		(pad "217" smd rect
			(at 2.050034 -2.124964 270)
			(size 0.519938 1.4986)
			(layers "F.Cu" "F.Mask" "F.Paste")
			(net "M_A_CPU0_CLK_DP<0>")
		)
		(pad "218" smd rect
			(at 2.050034 -1.27508 270)
			(size 0.519938 1.4986)
			(layers "F.Cu" "F.Mask" "F.Paste")
			(net "M_A_CPU0_CLK_DN<0>")
		)
		(pad "219" smd rect
			(at 2.050034 -0.424942 270)
			(size 0.519938 1.4986)
			(layers "F.Cu" "F.Mask" "F.Paste")
			(net "GND")
		)
		(pad "220" smd rect
			(at 2.050034 5.525008 270)
			(size 0.519938 1.4986)
			(layers "F.Cu" "F.Mask" "F.Paste")
			(net "TP_CHA_CPU0_DIMM1_FRU_4")
		)
		(pad "221" smd rect
			(at 2.050034 6.374892 270)
			(size 0.519938 1.4986)
			(layers "F.Cu" "F.Mask" "F.Paste")
			(net "M_A_CPU0_SB_CA<1>")
		)
		(pad "222" smd rect
			(at 2.050034 7.22503 270)
			(size 0.519938 1.4986)
			(layers "F.Cu" "F.Mask" "F.Paste")
			(net "GND")
		)
		(pad "223" smd rect
			(at 2.050034 8.074914 270)
			(size 0.519938 1.4986)
			(layers "F.Cu" "F.Mask" "F.Paste")
			(net "M_A_CPU0_SB_CA<3>")
		)
		(pad "224" smd rect
			(at 2.050034 8.925052 270)
			(size 0.519938 1.4986)
			(layers "F.Cu" "F.Mask" "F.Paste")
			(net "GND")
		)
	)
)
